# S9S_MB_2U (Grand Teton) — schematic netlist excerpt (pin names and nets, part order shuffled) for the footprints in the layout excerpt that follows; sources: Cadence DE-HDL packaged netlist, KiCad conversion of 03242023_DA0F0TMBIJ0_F0T_Motherboard_J_brd_V01_OCP.brd

PR259  Q_RES  8.45K 1% CHIP  pkg 0402LF  page 292 : A = PVCCINFAON_CPU1_ADDR ; B = GND
R941  Q_RES  10K 1% CHIP  pkg 0402LF  page 115 : A = P3V3_AUX ; B = PWRGD_FAIL_CPU0_CD_R1

(kicad_pcb
	(version 20260206)
	(generator "pcbnew")
	(generator_version "10.0")
	(general
		(thickness 1.6)
		(legacy_teardrops no)
	)
	(paper "A4")
	(title_block
		(title "03242023_DA0F0TMBIJ0_F0T_Motherboard_J_brd_V01_OCP.brd")
		(comment 1 "Grand Teton / footprints 5726-5727 of 6105")
	)
	(layers
		(0 "F.Cu" signal "TOP")
		(4 "In1.Cu" signal "GND")
		(6 "In2.Cu" signal "IN1")
		(8 "In3.Cu" signal "GND1")
		(10 "In4.Cu" signal "IN2")
		(12 "In5.Cu" signal "GND2")
		(14 "In6.Cu" signal "IN3")
		(16 "In7.Cu" signal "GND3")
		(18 "In8.Cu" signal "VCC")
		(20 "In9.Cu" signal "VCC1")
		(22 "In10.Cu" signal "GND4")
		(24 "In11.Cu" signal "IN4")
		(26 "In12.Cu" signal "GND5")
		(28 "In13.Cu" signal "IN5")
		(30 "In14.Cu" signal "GND6")
		(32 "In15.Cu" signal "IN6")
		(34 "In16.Cu" signal "GND7")
		(2 "B.Cu" signal "BOTTOM")
		(9 "F.Adhes" user "F.Adhesive")
		(11 "B.Adhes" user "B.Adhesive")
		(13 "F.Paste" user "Package Geometry/Pastemask Top")
		(15 "B.Paste" user "Package Geometry/Pastemask Bottom")
		(5 "F.SilkS" user "Ref Des/Silkscreen Top")
		(7 "B.SilkS" user "Ref Des/Silkscreen Bottom")
		(1 "F.Mask" user "Board Geometry/Soldermask Top")
		(3 "B.Mask" user "Board Geometry/Soldermask Bottom")
		(17 "Dwgs.User" user "User.Drawings")
		(19 "Cmts.User" user "User.Comments")
		(21 "Eco1.User" user "User.Eco1")
		(23 "Eco2.User" user "User.Eco2")
		(25 "Edge.Cuts" user "Board Geometry/Outline")
		(27 "Margin" user)
		(31 "F.CrtYd" user "Package Geometry/Place Bound Top")
		(29 "B.CrtYd" user "Package Geometry/Place Bound Bottom")
		(35 "F.Fab" user "Ref Des/Assembly Top")
		(33 "B.Fab" user "Ref Des/Assembly Bottom")
	)
	(footprint ""
		(layer "B.Cu")
		(at 27.0383 -130.396996)
		(property "Reference" "PR259"
			(at 0 0 0)
			(layer "B.SilkS")
			(hide yes)
			(effects
				(font
					(size 1.27 1.27)
				)
				(justify mirror)
			)
		)
		(property "Value" ""
			(at 0 0 0)
			(layer "B.Fab")
			(effects
				(font
					(size 1.27 1.27)
				)
				(justify mirror)
			)
		)
		(duplicate_pad_numbers_are_jumpers no)
		(fp_line
			(start -0.7874 -0.4064)
			(end -0.7874 0.4064)
			(stroke
				(width 0.1524)
				(type default)
			)
			(layer "B.SilkS")
		)
		(fp_line
			(start -0.7874 0.4064)
			(end 0.7874 0.4064)
			(stroke
				(width 0.1524)
				(type default)
			)
			(layer "B.SilkS")
		)
		(fp_line
			(start 0.7874 -0.4064)
			(end -0.7874 -0.4064)
			(stroke
				(width 0.1524)
				(type default)
			)
			(layer "B.SilkS")
		)
		(fp_line
			(start 0.7874 0.4064)
			(end 0.7874 -0.4064)
			(stroke
				(width 0.1524)
				(type default)
			)
			(layer "B.SilkS")
		)
		(fp_line
			(start -0.67945 -0.3048)
			(end -0.67945 0.3048)
			(stroke
				(width 0.1)
				(type default)
			)
			(layer "B.Fab")
		)
		(fp_line
			(start -0.67945 0.3048)
			(end -0.120396 0.3048)
			(stroke
				(width 0.1)
				(type default)
			)
			(layer "B.Fab")
		)
		(fp_line
			(start -0.12065 -0.3048)
			(end -0.67945 -0.3048)
			(stroke
				(width 0.1)
				(type default)
			)
			(layer "B.Fab")
		)
		(fp_line
			(start -0.12065 -0.2794)
			(end -0.12065 -0.3048)
			(stroke
				(width 0.1)
				(type default)
			)
			(layer "B.Fab")
		)
		(fp_line
			(start -0.120396 0.2794)
			(end 0.12065 0.2794)
			(stroke
				(width 0.1)
				(type default)
			)
			(layer "B.Fab")
		)
		(fp_line
			(start -0.120396 0.3048)
			(end -0.120396 0.2794)
			(stroke
				(width 0.1)
				(type default)
			)
			(layer "B.Fab")
		)
		(fp_line
			(start 0.12065 -0.305054)
			(end 0.12065 -0.2794)
			(stroke
				(width 0.1)
				(type default)
			)
			(layer "B.Fab")
		)
		(fp_line
			(start 0.12065 -0.2794)
			(end -0.12065 -0.2794)
			(stroke
				(width 0.1)
				(type default)
			)
			(layer "B.Fab")
		)
		(fp_line
			(start 0.12065 0.2794)
			(end 0.12065 0.3048)
			(stroke
				(width 0.1)
				(type default)
			)
			(layer "B.Fab")
		)
		(fp_line
			(start 0.12065 0.3048)
			(end 0.67945 0.3048)
			(stroke
				(width 0.1)
				(type default)
			)
			(layer "B.Fab")
		)
		(fp_line
			(start 0.67945 -0.305054)
			(end 0.12065 -0.305054)
			(stroke
				(width 0.1)
				(type default)
			)
			(layer "B.Fab")
		)
		(fp_line
			(start 0.67945 0.3048)
			(end 0.67945 -0.305054)
			(stroke
				(width 0.1)
				(type default)
			)
			(layer "B.Fab")
		)
		(pad "1" smd circle
			(at 0.40005 0 180)
			(size 0 0)
			(layers "B.Cu" "B.Mask" "B.Paste")
			(net "PVCCINFAON_CPU1_ADDR")
		)
		(pad "2" smd circle
			(at -0.40005 0 180)
			(size 0 0)
			(layers "B.Cu" "B.Mask" "B.Paste")
			(net "GND")
		)
	)
	(footprint ""
		(layer "B.Cu")
		(at 284.075378 -319.392046)
		(property "Reference" "R941"
			(at 0 0 0)
			(layer "B.SilkS")
			(hide yes)
			(effects
				(font
					(size 1.27 1.27)
				)
				(justify mirror)
			)
		)
		(property "Value" ""
			(at 0 0 0)
			(layer "B.Fab")
			(effects
				(font
					(size 1.27 1.27)
				)
				(justify mirror)
			)
		)
		(duplicate_pad_numbers_are_jumpers no)
		(fp_line
			(start -0.7874 -0.4064)
			(end -0.7874 0.4064)
			(stroke
				(width 0.1524)
				(type default)
			)
			(layer "B.SilkS")
		)
		(fp_line
			(start -0.7874 0.4064)
			(end 0.7874 0.4064)
			(stroke
				(width 0.1524)
				(type default)
			)
			(layer "B.SilkS")
		)
		(fp_line
			(start 0.7874 -0.4064)
			(end -0.7874 -0.4064)
			(stroke
				(width 0.1524)
				(type default)
			)
			(layer "B.SilkS")
		)
		(fp_line
			(start 0.7874 0.4064)
			(end 0.7874 -0.4064)
			(stroke
				(width 0.1524)
				(type default)
			)
			(layer "B.SilkS")
		)
		(fp_line
			(start -0.67945 -0.3048)
			(end -0.67945 0.3048)
			(stroke
				(width 0.1)
				(type default)
			)
			(layer "B.Fab")
		)
		(fp_line
			(start -0.67945 0.3048)
			(end -0.120396 0.3048)
			(stroke
				(width 0.1)
				(type default)
			)
			(layer "B.Fab")
		)
		(fp_line
			(start -0.12065 -0.3048)
			(end -0.67945 -0.3048)
			(stroke
				(width 0.1)
				(type default)
			)
			(layer "B.Fab")
		)
		(fp_line
			(start -0.12065 -0.2794)
			(end -0.12065 -0.3048)
			(stroke
				(width 0.1)
				(type default)
			)
			(layer "B.Fab")
		)
		(fp_line
			(start -0.120396 0.2794)
			(end 0.12065 0.2794)
			(stroke
				(width 0.1)
				(type default)
			)
			(layer "B.Fab")
		)
		(fp_line
			(start -0.120396 0.3048)
			(end -0.120396 0.2794)
			(stroke
				(width 0.1)
				(type default)
			)
			(layer "B.Fab")
		)
		(fp_line
			(start 0.12065 -0.305054)
			(end 0.12065 -0.2794)
			(stroke
				(width 0.1)
				(type default)
			)
			(layer "B.Fab")
		)
		(fp_line
			(start 0.12065 -0.2794)
			(end -0.12065 -0.2794)
			(stroke
				(width 0.1)
				(type default)
			)
			(layer "B.Fab")
		)
		(fp_line
			(start 0.12065 0.2794)
			(end 0.12065 0.3048)
			(stroke
				(width 0.1)
				(type default)
			)
			(layer "B.Fab")
		)
		(fp_line
			(start 0.12065 0.3048)
			(end 0.67945 0.3048)
			(stroke
				(width 0.1)
				(type default)
			)
			(layer "B.Fab")
		)
		(fp_line
			(start 0.67945 -0.305054)
			(end 0.12065 -0.305054)
			(stroke
				(width 0.1)
				(type default)
			)
			(layer "B.Fab")
		)
		(fp_line
			(start 0.67945 0.3048)
			(end 0.67945 -0.305054)
			(stroke
				(width 0.1)
				(type default)
			)
			(layer "B.Fab")
		)
		(pad "1" smd circle
			(at 0.40005 0 180)
			(size 0 0)
			(layers "B.Cu" "B.Mask" "B.Paste")
			(net "P3V3_AUX")
		)
		(pad "2" smd circle
			(at -0.40005 0 180)
			(size 0 0)
			(layers "B.Cu" "B.Mask" "B.Paste")
			(net "PWRGD_FAIL_CPU0_CD_R1")
		)
	)
)
